(kicad_pcb
	(version 20221018)
	(generator pcbnew)
	(general
    (thickness 0.908)
  )
	(paper "A4")
	(title_block
    (title "HDMI-MIPI Bridge")
    (date "2024-04-24")
    (rev "1.3.2")
		(comment 9 "footprints 27-33 of 121")
	)
	(layers
    (0 "F.Cu" signal)
    (1 "In1.Cu" signal)
    (2 "In2.Cu" signal)
    (31 "B.Cu" signal)
    (32 "B.Adhes" user "B.Adhesive")
    (33 "F.Adhes" user "F.Adhesive")
    (34 "B.Paste" user)
    (35 "F.Paste" user)
    (36 "B.SilkS" user "B.Silkscreen")
    (37 "F.SilkS" user "F.Silkscreen")
    (38 "B.Mask" user)
    (39 "F.Mask" user)
    (40 "Dwgs.User" user "User.Drawings")
    (41 "Cmts.User" user "User.Comments")
    (42 "Eco1.User" user "User.Eco1")
    (43 "Eco2.User" user "User.Eco2")
    (44 "Edge.Cuts" user)
    (45 "Margin" user)
    (46 "B.CrtYd" user "B.Courtyard")
    (47 "F.CrtYd" user "F.Courtyard")
    (48 "B.Fab" user)
    (49 "F.Fab" user)
  )
	(footprint "antmicro-footprints:C_0402_1005Metric" (layer "F.Cu")
    (at 163.79 108.21)
    (descr "Capacitor SMD 0402")
    (tags "capacitor SMD 0402")
    (property "Author" "Antmicro")
    (property "Dielectric" "")
    (property "License" "Apache-2.0")
    (property "MPN" "0402B471K250CT")
    (property "Manufacturer" "Walsin")
    (property "Public" "False")
    (property "Sheetfile" "channel2.kicad_sch")
    (property "Sheetname" "Channel 2")
    (property "Val" "470p")
    (property "Voltage" "")
    (property "ki_description" "SMD Multilayer Ceramic Capacitor, General Purpose, 470 pF, 25 V, 0402 [1005 Metric], ± 10%, X7R")
    (property "ki_keywords" "0402, SMT, CAPACITOR, PASSIVE, MLCC")
    (attr smd)
    (fp_text reference "C48" (at -3.69 7.06) (layer "F.SilkS")
        (effects (font (size 0.65 0.65) (thickness 0.13)) (justify left bottom))
    )
    (fp_text value "C_470p_0402" (at 0 1.4) (layer "F.Fab")
        (effects (font (size 0.65 0.65) (thickness 0.13)) (justify left bottom))
    )
    (fp_text user "Author: Antmicro" (at -0.932 4.17) (layer "F.Fab") hide
        (effects (font (size 0.7 0.7) (thickness 0.15)) (justify left bottom))
    )
    (fp_text user "License: Apache-2.0" (at -0.932 5.17) (layer "F.Fab") hide
        (effects (font (size 0.7 0.7) (thickness 0.15)) (justify left bottom))
    )
    (fp_text user "${REFERENCE}" (at -0.932 3.168) (layer "F.Fab") hide
        (effects (font (size 0.7 0.7) (thickness 0.15)) (justify left bottom))
    )
    (fp_rect (start -0.925 -0.47) (end 0.925 0.47)
      (stroke (width 0.05) (type default)) (fill none) (layer "F.CrtYd"))
    (fp_line (start -0.494 -0.25) (end 0.504 -0.25)
      (stroke (width 0.15) (type solid)) (layer "F.Fab"))
    (fp_line (start -0.494 0.248) (end -0.494 -0.25)
      (stroke (width 0.15) (type solid)) (layer "F.Fab"))
    (fp_line (start 0.504 -0.25) (end 0.504 0.248)
      (stroke (width 0.15) (type solid)) (layer "F.Fab"))
    (fp_line (start 0.504 0.248) (end -0.494 0.248)
      (stroke (width 0.15) (type solid)) (layer "F.Fab"))
    (pad "1" smd roundrect (at -0.48 0) (size 0.59 0.64) (layers "F.Cu" "F.Paste" "F.Mask") (roundrect_rratio 0.25)
      (net 109 "Net-(C48-Pad1)") (pintype "passive"))
    (pad "2" smd roundrect (at 0.48 0) (size 0.59 0.64) (layers "F.Cu" "F.Paste" "F.Mask") (roundrect_rratio 0.25)
      (net 2 "GND") (pintype "passive"))
  )
	(footprint "antmicro-footprints:FB_0805_2012Metric" (layer "F.Cu")
    (at 166.6 108.75 90)
    (descr "FERRITE BEAD 0805")
    (tags "FERRITE BEAD 0805")
    (property "Author" "Antmicro")
    (property "Current" "")
    (property "License" "Apache-2.0")
    (property "MPN" "742792096")
    (property "Manufacturer" "Würth Elektronik")
    (property "Public" "False")
    (property "Sheetfile" "channel2.kicad_sch")
    (property "Sheetname" "Channel 2")
    (property "Val" "1kZ/0.8A")
    (property "ki_description" "Ferrite Beads WE-CBF 0805 100MHz 1kOhm 1A, High Current")
    (property "ki_keywords" "FERRITE BEAD, PASSIVE")
    (attr smd)
    (fp_text reference "FB9" (at -2.32 1.77 90) (layer "F.SilkS")
        (effects (font (size 0.65 0.65) (thickness 0.13)) (justify left bottom))
    )
    (fp_text value "FB_1kZ_0.8A_WE-CBF_0805" (at 0 1.8 90) (layer "F.Fab")
        (effects (font (size 0.65 0.65) (thickness 0.13)) (justify left bottom))
    )
    (fp_text user "${REFERENCE}" (at -1.9 3.1 90) (layer "F.Fab") hide
        (effects (font (size 0.7 0.7) (thickness 0.15)) (justify left bottom))
    )
    (fp_text user "Author: Antmicro" (at -1.9 4.4 90) (layer "F.Fab") hide
        (effects (font (size 0.7 0.7) (thickness 0.15)) (justify left bottom))
    )
    (fp_text user "License: Apache-2.0" (at -1.9 5.75 90) (layer "F.Fab") hide
        (effects (font (size 0.7 0.7) (thickness 0.15)) (justify left bottom))
    )
    (fp_line (start -0.319 0.698) (end 0.281 0.698)
      (stroke (width 0.15) (type solid)) (layer "F.SilkS"))
    (fp_line (start -0.299 -0.698) (end 0.299 -0.698)
      (stroke (width 0.15) (type solid)) (layer "F.SilkS"))
    (fp_rect (start 1.95 -0.9) (end -1.95 0.9)
      (stroke (width 0.05) (type default)) (fill none) (layer "F.CrtYd"))
    (fp_line (start -0.948 -0.681) (end 0.948 -0.681)
      (stroke (width 0.15) (type solid)) (layer "F.Fab"))
    (fp_line (start -0.948 -0.676) (end -0.948 0.676)
      (stroke (width 0.15) (type solid)) (layer "F.Fab"))
    (fp_line (start -0.948 0.681) (end 0.948 0.681)
      (stroke (width 0.15) (type solid)) (layer "F.Fab"))
    (fp_line (start 0.948 -0.676) (end 0.948 0.676)
      (stroke (width 0.15) (type solid)) (layer "F.Fab"))
    (pad "1" smd roundrect (at -1.1 0 90) (size 1.2 1.3) (layers "F.Cu" "F.Paste" "F.Mask") (roundrect_rratio 0.25)
      (net 109 "Net-(C48-Pad1)") (pintype "passive"))
    (pad "2" smd roundrect (at 1.1 0 90) (size 1.2 1.3) (layers "F.Cu" "F.Paste" "F.Mask") (roundrect_rratio 0.25)
      (net 25 "CH2_1V2") (pintype "passive"))
  )
	(footprint "antmicro-footprints:C_0603_1608Metric" (layer "F.Cu")
    (at 140.15 109.48 180)
    (descr "Capacitor SMD 0603")
    (tags "capacitor 0603")
    (property "Author" "Antmicro")
    (property "Dielectric" "")
    (property "License" "Apache-2.0")
    (property "MPN" "C1608X5R1V475M080AC")
    (property "Manufacturer" "TDK")
    (property "Public" "False")
    (property "Sheetfile" "channel1.kicad_sch")
    (property "Sheetname" "Channel 1")
    (property "Val" "4u7")
    (property "Voltage" "")
    (property "ki_description" "SMD Multilayer Ceramic Capacitor, 4.7 µF, 35 V, 0603 [1608 Metric], ± 20%, X5R, C")
    (property "ki_keywords" "0603, SMT, CAPACITOR, PASSIVE, CERAMIC, MLCC")
    (attr smd)
    (fp_text reference "C8" (at 2.6 -5.8) (layer "F.SilkS")
        (effects (font (size 0.65 0.65) (thickness 0.13)) (justify right bottom))
    )
    (fp_text value "C_4u7_0603" (at 0 1.6) (layer "F.Fab")
        (effects (font (size 0.65 0.65) (thickness 0.13)) (justify right bottom))
    )
    (fp_text user "${REFERENCE}" (at -1.682 3.895) (layer "F.Fab") hide
        (effects (font (size 0.7 0.7) (thickness 0.15)) (justify right bottom))
    )
    (fp_text user "License: Apache-2.0" (at -1.682 5.895) (layer "F.Fab") hide
        (effects (font (size 0.7 0.7) (thickness 0.15)) (justify right bottom))
    )
    (fp_text user "Author: Antmicro" (at -1.682 4.894) (layer "F.Fab") hide
        (effects (font (size 0.7 0.7) (thickness 0.15)) (justify right bottom))
    )
    (fp_line (start -0.15 -0.4) (end 0.15 -0.4)
      (stroke (width 0.15) (type solid)) (layer "F.SilkS"))
    (fp_line (start -0.15 0.4) (end 0.15 0.4)
      (stroke (width 0.15) (type solid)) (layer "F.SilkS"))
    (fp_rect (start -1.25 -0.65) (end 1.25 0.65)
      (stroke (width 0.05) (type solid)) (fill none) (layer "F.CrtYd"))
    (fp_rect (start -0.8 -0.4) (end 0.8 0.4)
      (stroke (width 0.15) (type solid)) (fill none) (layer "F.Fab"))
    (pad "1" smd roundrect (at -0.7 0 180) (size 0.8 1) (layers "F.Cu" "F.Paste" "F.Mask") (roundrect_rratio 0.2)
      (net 2 "GND") (pintype "passive"))
    (pad "2" smd roundrect (at 0.7 0 180) (size 0.8 1) (layers "F.Cu" "F.Paste" "F.Mask") (roundrect_rratio 0.2)
      (net 5 "Net-(U1B-AVDD25)") (pintype "passive"))
  )
	(footprint "antmicro-footprints:FB_0603_1608Metric" (layer "F.Cu")
    (at 147.81 107.86 -90)
    (property "Author" "Antmicro")
    (property "Current" "")
    (property "License" "Apache-2.0")
    (property "MPN" "BLM18AG601SN1D")
    (property "Manufacturer" "Murata")
    (property "Public" "False")
    (property "Sheetfile" "channel2.kicad_sch")
    (property "Sheetname" "Channel 2")
    (property "Val" "600Z/0.5A")
    (property "ki_description" "Ferrite Bead, 0603 [1608 Metric], 600 ohm, 500 mA, BLM18A, 0.38 ohm, ± 25%, General use")
    (property "ki_keywords" "0603, SMT, FERRITE BEAD, PASSIVE")
    (attr smd)
    (fp_text reference "FB12" (at 1.54 0.61 -90) (layer "F.SilkS")
        (effects (font (size 0.65 0.65) (thickness 0.13)) (justify left bottom))
    )
    (fp_text value "FB_600Z_0.5A_Murata-BLM18AG_0603" (at 0 1.5 -90) (layer "F.Fab")
        (effects (font (size 0.65 0.65) (thickness 0.13)) (justify left bottom))
    )
    (fp_text user "${REFERENCE}" (at -1.653 4.6 -90) (layer "F.Fab") hide
        (effects (font (size 0.7 0.7) (thickness 0.15)) (justify left bottom))
    )
    (fp_text user "Author: Antmicro" (at -1.653 3.162 -90) (layer "F.Fab") hide
        (effects (font (size 0.7 0.7) (thickness 0.15)) (justify left bottom))
    )
    (fp_text user "License: Apache-2.0" (at -1.653 5.9 -90) (layer "F.Fab") hide
        (effects (font (size 0.7 0.7) (thickness 0.15)) (justify left bottom))
    )
    (fp_line (start -0.15 -0.4) (end 0.15 -0.4)
      (stroke (width 0.15) (type solid)) (layer "F.SilkS"))
    (fp_line (start -0.15 0.4) (end 0.15 0.4)
      (stroke (width 0.15) (type solid)) (layer "F.SilkS"))
    (fp_rect (start -1.25 -0.65) (end 1.25 0.65)
      (stroke (width 0.05) (type solid)) (fill none) (layer "F.CrtYd"))
    (fp_line (start -0.803 0.406) (end -0.803 -0.408)
      (stroke (width 0.15) (type solid)) (layer "F.Fab"))
    (fp_line (start 0.8 -0.408) (end -0.803 -0.408)
      (stroke (width 0.15) (type solid)) (layer "F.Fab"))
    (fp_line (start 0.8 -0.408) (end 0.8 0.406)
      (stroke (width 0.15) (type solid)) (layer "F.Fab"))
    (fp_line (start 0.8 0.406) (end -0.803 0.406)
      (stroke (width 0.15) (type solid)) (layer "F.Fab"))
    (pad "1" smd roundrect (at -0.7 0 270) (size 0.8 1) (layers "F.Cu" "F.Paste" "F.Mask") (roundrect_rratio 0.2)
      (net 9 "+3V3") (pintype "passive"))
    (pad "2" smd roundrect (at 0.7 0 270) (size 0.8 1) (layers "F.Cu" "F.Paste" "F.Mask") (roundrect_rratio 0.2)
      (net 30 "Net-(Y2-EN)") (pintype "passive"))
  )
	(footprint "antmicro-footprints:C_0402_1005Metric" (layer "F.Cu")
    (at 163.39 104.21 90)
    (descr "Capacitor SMD 0402")
    (tags "capacitor SMD 0402")
    (property "Author" "Antmicro")
    (property "Dielectric" "X5R")
    (property "License" "Apache-2.0")
    (property "MPN" "GRM155R61H104KE14D")
    (property "Manufacturer" "Murata")
    (property "Public" "False")
    (property "Sheetfile" "channel2.kicad_sch")
    (property "Sheetname" "Channel 2")
    (property "Val" "100n")
    (property "Voltage" "50V")
    (property "ki_description" "SMD Multilayer Ceramic Capacitor, 0.1 µF, 50 V, 0402 [1005 Metric], ± 10%, X5R, GRM Series")
    (property "ki_keywords" "0402, SMT, CAPACITOR, PASSIVE, CERAMIC, MLCC")
    (attr smd)
    (fp_text reference "C45" (at 5.16 -11.68 90) (layer "F.SilkS")
        (effects (font (size 0.65 0.65) (thickness 0.13)) (justify right bottom))
    )
    (fp_text value "C_100n_0402" (at 0 1.4 90) (layer "F.Fab")
        (effects (font (size 0.65 0.65) (thickness 0.13)) (justify left bottom))
    )
    (fp_text user "License: Apache-2.0" (at -0.932 5.17 90) (layer "F.Fab") hide
        (effects (font (size 0.7 0.7) (thickness 0.15)) (justify left bottom))
    )
    (fp_text user "${REFERENCE}" (at -0.932 3.168 90) (layer "F.Fab") hide
        (effects (font (size 0.7 0.7) (thickness 0.15)) (justify left bottom))
    )
    (fp_text user "Author: Antmicro" (at -0.932 4.17 90) (layer "F.Fab") hide
        (effects (font (size 0.7 0.7) (thickness 0.15)) (justify left bottom))
    )
    (fp_rect (start -0.925 -0.47) (end 0.925 0.47)
      (stroke (width 0.05) (type default)) (fill none) (layer "F.CrtYd"))
    (fp_line (start -0.494 -0.25) (end 0.504 -0.25)
      (stroke (width 0.15) (type solid)) (layer "F.Fab"))
    (fp_line (start -0.494 0.248) (end -0.494 -0.25)
      (stroke (width 0.15) (type solid)) (layer "F.Fab"))
    (fp_line (start 0.504 -0.25) (end 0.504 0.248)
      (stroke (width 0.15) (type solid)) (layer "F.Fab"))
    (fp_line (start 0.504 0.248) (end -0.494 0.248)
      (stroke (width 0.15) (type solid)) (layer "F.Fab"))
    (pad "1" smd roundrect (at -0.48 0 90) (size 0.59 0.64) (layers "F.Cu" "F.Paste" "F.Mask") (roundrect_rratio 0.25)
      (net 2 "GND") (pintype "passive"))
    (pad "2" smd roundrect (at 0.48 0 90) (size 0.59 0.64) (layers "F.Cu" "F.Paste" "F.Mask") (roundrect_rratio 0.25)
      (net 14 "+5V") (pintype "passive"))
  )
	(footprint "antmicro-footprints:SOT-23-5" (layer "F.Cu")
    (at 172.25 115.95 90)
    (property "Author" "Antmicro")
    (property "License" "Apache-2.0")
    (property "MPN" "TLV73325PDBVT")
    (property "Manufacturer" "Texas Instruments")
    (property "Sheetfile" "channel2.kicad_sch")
    (property "Sheetname" "Channel 2")
    (property "ki_description" "Linear voltage regulator")
    (property "ki_keywords" "SMT, PMIC, IC, LDO, LINEAR, VOLTAGE, REGULATOR")
    (attr smd)
    (fp_text reference "IC3" (at -1.1 2.72 90) (layer "F.SilkS")
        (effects (font (size 0.65 0.65) (thickness 0.13)) (justify left bottom))
    )
    (fp_text value "TLV73325PDBVT" (at 0.002 2.799 90) (layer "F.Fab")
        (effects (font (size 0.65 0.65) (thickness 0.13)) (justify left bottom))
    )
    (fp_text user "${REFERENCE}" (at -1.898 4.299 90) (layer "F.Fab") hide
        (effects (font (size 0.7 0.7) (thickness 0.15)) (justify left bottom))
    )
    (fp_text user "License: Apache-2.0" (at -1.898 6.7 90) (layer "F.Fab") hide
        (effects (font (size 0.7 0.7) (thickness 0.15)) (justify left bottom))
    )
    (fp_text user "Author: Antmicro" (at -1.898 5.499 90) (layer "F.Fab") hide
        (effects (font (size 0.7 0.7) (thickness 0.15)) (justify left bottom))
    )
    (fp_line (start -0.85 1.6) (end -0.85 1.301)
      (stroke (width 0.15) (type solid)) (layer "F.SilkS"))
    (fp_line (start -0.8 -1.6) (end -0.8 -1.3)
      (stroke (width 0.15) (type solid)) (layer "F.SilkS"))
    (fp_line (start -0.8 -1.6) (end -0.5 -1.6)
      (stroke (width 0.15) (type solid)) (layer "F.SilkS"))
    (fp_line (start -0.55 1.6) (end -0.85 1.6)
      (stroke (width 0.15) (type solid)) (layer "F.SilkS"))
    (fp_line (start 0.8 -1.6) (end 0.5 -1.6)
      (stroke (width 0.15) (type solid)) (layer "F.SilkS"))
    (fp_line (start 0.8 -1.3) (end 0.8 -1.6)
      (stroke (width 0.15) (type solid)) (layer "F.SilkS"))
    (fp_line (start 0.8 0.55) (end 0.8 -0.55)
      (stroke (width 0.15) (type solid)) (layer "F.SilkS"))
    (fp_line (start 0.8 1.3) (end 0.8 1.599)
      (stroke (width 0.15) (type solid)) (layer "F.SilkS"))
    (fp_line (start 0.8 1.599) (end 0.549 1.599)
      (stroke (width 0.15) (type solid)) (layer "F.SilkS"))
    (fp_circle (center -1.25 -1.5) (end -1.2 -1.5)
      (stroke (width 0.15) (type solid)) (fill solid) (layer "F.SilkS"))
    (fp_rect (start 1.9 -1.76) (end -1.9 1.75)
      (stroke (width 0.05) (type solid)) (fill none) (layer "F.CrtYd"))
    (fp_line (start -0.398 -1.526) (end -0.874 -1.05)
      (stroke (width 0.15) (type solid)) (layer "F.Fab"))
    (fp_rect (start 0.874 1.523) (end -0.873 -1.525)
      (stroke (width 0.15) (type solid)) (fill none) (layer "F.Fab"))
    (pad "1" smd rect (at -1.351 -0.951) (size 0.55 1) (layers "F.Cu" "F.Paste" "F.Mask")
      (net 9 "+3V3") (pinfunction "VIN") (pintype "power_in"))
    (pad "2" smd rect (at -1.351 0) (size 0.55 1) (layers "F.Cu" "F.Paste" "F.Mask")
      (net 2 "GND") (pinfunction "GND") (pintype "power_in"))
    (pad "3" smd rect (at -1.351 0.949) (size 0.55 1) (layers "F.Cu" "F.Paste" "F.Mask")
      (net 9 "+3V3") (pinfunction "EN") (pintype "input"))
    (pad "4" smd rect (at 1.35 0.949) (size 0.55 1) (layers "F.Cu" "F.Paste" "F.Mask")
      (net 102 "unconnected-(IC3-NC-Pad4)") (pinfunction "NC") (pintype "no_connect"))
    (pad "5" smd rect (at 1.35 -0.951) (size 0.55 1) (layers "F.Cu" "F.Paste" "F.Mask")
      (net 24 "CH2_2V5") (pinfunction "VOUT") (pintype "power_out"))
  )
	(footprint "antmicro-footprints:C_0603_1608Metric" (layer "F.Cu")
    (at 171.65 113.05 180)
    (descr "Capacitor SMD 0603")
    (tags "capacitor 0603")
    (property "Author" "Antmicro")
    (property "Dielectric" "template_dielectric")
    (property "License" "Apache-2.0")
    (property "MPN" "GRM188R61A106KE69D")
    (property "Manufacturer" "Murata")
    (property "Public" "False")
    (property "Sheetfile" "channel2.kicad_sch")
    (property "Sheetname" "Channel 2")
    (property "Val" "10u")
    (property "Voltage" "")
    (property "ki_description" "SMD Multilayer Ceramic Capacitor, 10 µF, 10 V, 0603 [1608 Metric], ± 10%, X5R, GRM Series")
    (property "ki_keywords" "0603, SMT, CAPACITOR, PASSIVE, CERAMIC, MLCC")
    (attr smd)
    (fp_text reference "C42" (at -0.95 0.65) (layer "F.SilkS")
        (effects (font (size 0.65 0.65) (thickness 0.13)) (justify right bottom))
    )
    (fp_text value "C_10u_0603" (at 0 1.6) (layer "F.Fab")
        (effects (font (size 0.65 0.65) (thickness 0.13)) (justify right bottom))
    )
    (fp_text user "${REFERENCE}" (at -1.682 3.895) (layer "F.Fab") hide
        (effects (font (size 0.7 0.7) (thickness 0.15)) (justify right bottom))
    )
    (fp_text user "Author: Antmicro" (at -1.682 4.894) (layer "F.Fab") hide
        (effects (font (size 0.7 0.7) (thickness 0.15)) (justify right bottom))
    )
    (fp_text user "License: Apache-2.0" (at -1.682 5.895) (layer "F.Fab") hide
        (effects (font (size 0.7 0.7) (thickness 0.15)) (justify right bottom))
    )
    (fp_line (start -0.15 -0.4) (end 0.15 -0.4)
      (stroke (width 0.15) (type solid)) (layer "F.SilkS"))
    (fp_line (start -0.15 0.4) (end 0.15 0.4)
      (stroke (width 0.15) (type solid)) (layer "F.SilkS"))
    (fp_rect (start -1.25 -0.65) (end 1.25 0.65)
      (stroke (width 0.05) (type solid)) (fill none) (layer "F.CrtYd"))
    (fp_rect (start -0.8 -0.4) (end 0.8 0.4)
      (stroke (width 0.15) (type solid)) (fill none) (layer "F.Fab"))
    (pad "1" smd roundrect (at -0.7 0 180) (size 0.8 1) (layers "F.Cu" "F.Paste" "F.Mask") (roundrect_rratio 0.2)
      (net 2 "GND") (pintype "passive"))
    (pad "2" smd roundrect (at 0.7 0 180) (size 0.8 1) (layers "F.Cu" "F.Paste" "F.Mask") (roundrect_rratio 0.2)
      (net 24 "CH2_2V5") (pintype "passive"))
  )
)
